(kicad_pcb
	(version 20260206)
	(generator "pcbnew")
	(generator_version "10.0")
	(general
		(thickness 1.6)
		(legacy_teardrops no)
	)
	(paper "A4")
	(title_block
		(title "Wiwynn_Tioga_Pass_MB.brd")
		(comment 1 "Tioga Pass / footprint 190 of 4770 (U2D1), pads 303-410 of 3647")
	)
	(layers
		(0 "F.Cu" signal "TOP")
		(4 "In1.Cu" signal "L2GND")
		(6 "In2.Cu" signal "L3")
		(8 "In3.Cu" signal "L4GND")
		(10 "In4.Cu" signal "L5")
		(12 "In5.Cu" signal "L6GND")
		(14 "In6.Cu" signal "L7VCC")
		(16 "In7.Cu" signal "L8VCC")
		(18 "In8.Cu" signal "L9GND")
		(20 "In9.Cu" signal "L10")
		(22 "In10.Cu" signal "L11GND")
		(24 "In11.Cu" signal "L12")
		(26 "In12.Cu" signal "L13GND")
		(2 "B.Cu" signal "BOTTOM")
		(9 "F.Adhes" user "F.Adhesive")
		(11 "B.Adhes" user "B.Adhesive")
		(13 "F.Paste" user "Package Geometry/Pastemask Top")
		(15 "B.Paste" user "Package Geometry/Pastemask Bottom")
		(5 "F.SilkS" user "Ref Des/Silkscreen Top")
		(7 "B.SilkS" user "Ref Des/Silkscreen Bottom")
		(1 "F.Mask" user "Board Geometry/Soldermask Top")
		(3 "B.Mask" user "Board Geometry/Soldermask Bottom")
		(17 "Dwgs.User" user "User.Drawings")
		(19 "Cmts.User" user "User.Comments")
		(21 "Eco1.User" user "User.Eco1")
		(23 "Eco2.User" user "User.Eco2")
		(25 "Edge.Cuts" user "Board Geometry/Outline")
		(27 "Margin" user)
		(31 "F.CrtYd" user "Package Geometry/Place Bound Top")
		(29 "B.CrtYd" user "Package Geometry/Place Bound Bottom")
		(35 "F.Fab" user "Ref Des/Assembly Top")
		(33 "B.Fab" user "Ref Des/Assembly Bottom")
	)
	(footprint ""
		(layer "F.Cu")
		(at 104.99979 -76.550012 180)
		(property "Reference" "U2D1"
			(at 25.19299 30.484318 0)
			(unlocked yes)
			(layer "F.SilkS")
			(effects
				(font
					(size 0.7874 0.5842)
					(thickness 0.1524)
				)
			)
		)
		(property "Value" ""
			(at 0 0 180)
			(layer "F.Fab")
			(effects
				(font
					(size 1.27 1.27)
				)
			)
		)
		(duplicate_pad_numbers_are_jumpers no)
		(pad "AG64" smd circle
			(at 18.363438 -14.025372)
			(size 0.4318 0.4318)
			(layers "F.Cu" "F.Mask" "F.Paste")
			(net "GND")
		)
		(pad "AG66" smd circle
			(at 20.080478 -14.025372)
			(size 0.4318 0.4318)
			(layers "F.Cu" "F.Mask" "F.Paste")
			(net "M_G_ECC<7>")
		)
		(pad "AG68" smd circle
			(at 21.797518 -14.025372)
			(size 0.4318 0.4318)
			(layers "F.Cu" "F.Mask" "F.Paste")
			(net "M_G_ECC<1>")
		)
		(pad "AG70" smd circle
			(at 23.514558 -14.025372)
			(size 0.4318 0.4318)
			(layers "F.Cu" "F.Mask" "F.Paste")
			(net "GND")
		)
		(pad "AG72" smd circle
			(at 25.231598 -14.025372)
			(size 0.4318 0.4318)
			(layers "F.Cu" "F.Mask" "F.Paste")
			(net "TP_CPU1_RSVD_234")
		)
		(pad "AG74" smd circle
			(at 26.948384 -14.025372)
			(size 0.4318 0.4318)
			(layers "F.Cu" "F.Mask" "F.Paste")
			(net "GND")
		)
		(pad "AG76" smd circle
			(at 28.665424 -14.025372)
			(size 0.4318 0.4318)
			(layers "F.Cu" "F.Mask" "F.Paste")
			(net "GND")
		)
		(pad "AG78" smd circle
			(at 30.382464 -14.025372)
			(size 0.4318 0.4318)
			(layers "F.Cu" "F.Mask" "F.Paste")
			(net "GND")
		)
		(pad "AG80" smd circle
			(at 32.099504 -14.025372)
			(size 0.4318 0.4318)
			(layers "F.Cu" "F.Mask" "F.Paste")
			(net "GND")
		)
		(pad "AG82" smd circle
			(at 33.816544 -14.025372)
			(size 0.4318 0.4318)
			(layers "F.Cu" "F.Mask" "F.Paste")
			(net "M_H_DQS_DN<10>")
		)
		(pad "AG84" smd circle
			(at 35.533584 -14.025372)
			(size 0.4318 0.4318)
			(layers "F.Cu" "F.Mask" "F.Paste")
			(net "M_G_DQ<7>")
		)
		(pad "AG86" smd custom
			(at 37.250624 -14.025372 270)
			(size 0.10795 0.10795)
			(layers "F.Cu" "F.Mask" "F.Paste")
			(net "M_G_DQ<6>")
			(options
				(clearance outline)
				(anchor circle)
			)
			(primitives
				(gr_poly
					(pts
						(arc
							(start 0.2159 -0.0381)
							(mid 0 -0.254)
							(end -0.2159 -0.0381)
						)
						(arc
							(start -0.2159 0.0381)
							(mid 0 0.254)
							(end 0.2159 0.0381)
						)
					)
					(width 0)
					(fill yes)
				)
			)
		)
		(pad "AH1" smd custom
			(at -37.250624 -11.730228 90)
			(size 0.10795 0.10795)
			(layers "F.Cu" "F.Mask" "F.Paste")
			(net "GND")
			(options
				(clearance outline)
				(anchor circle)
			)
			(primitives
				(gr_poly
					(pts
						(arc
							(start 0.2159 -0.0381)
							(mid 0 -0.254)
							(end -0.2159 -0.0381)
						)
						(arc
							(start -0.2159 0.0381)
							(mid 0 0.254)
							(end 0.2159 0.0381)
						)
					)
					(width 0)
					(fill yes)
				)
			)
		)
		(pad "AH3" smd circle
			(at -35.533584 -11.730228)
			(size 0.4318 0.4318)
			(layers "F.Cu" "F.Mask" "F.Paste")
			(net "UPI_CPU1_CPU0_P0P0_DP<8>")
		)
		(pad "AH5" smd circle
			(at -33.816544 -11.730228)
			(size 0.4318 0.4318)
			(layers "F.Cu" "F.Mask" "F.Paste")
			(net "GND")
		)
		(pad "AH7" smd circle
			(at -32.099504 -11.730228)
			(size 0.4318 0.4318)
			(layers "F.Cu" "F.Mask" "F.Paste")
			(net "UPI_CPU0_CPU1_P0P0_DN<6>")
		)
		(pad "AH9" smd circle
			(at -30.382464 -11.730228)
			(size 0.4318 0.4318)
			(layers "F.Cu" "F.Mask" "F.Paste")
			(net "PVCCIO_CPU1")
		)
		(pad "AH11" smd circle
			(at -28.665424 -11.730228)
			(size 0.4318 0.4318)
			(layers "F.Cu" "F.Mask" "F.Paste")
			(net "XDP_CPU_MBP1_N")
		)
		(pad "AH13" smd circle
			(at -26.948384 -11.730228)
			(size 0.4318 0.4318)
			(layers "F.Cu" "F.Mask" "F.Paste")
			(net "H_CPU1_MEMGHJ_MEMHOT_G_N")
		)
		(pad "AH15" smd circle
			(at -25.231598 -11.730228)
			(size 0.4318 0.4318)
			(layers "F.Cu" "F.Mask" "F.Paste")
			(net "TP_CPU1_RSVD_233")
		)
		(pad "AH19" smd circle
			(at -21.797518 -11.730228)
			(size 0.4318 0.4318)
			(layers "F.Cu" "F.Mask" "F.Paste")
			(net "TP_CPU1_RSVD_232")
		)
		(pad "AH21" smd circle
			(at -20.080478 -11.730228)
			(size 0.4318 0.4318)
			(layers "F.Cu" "F.Mask" "F.Paste")
			(net "GND")
		)
		(pad "AH23" smd circle
			(at -18.363438 -11.730228)
			(size 0.4318 0.4318)
			(layers "F.Cu" "F.Mask" "F.Paste")
			(net "M_J_DQ<63>")
		)
		(pad "AH25" smd circle
			(at -16.646398 -11.730228)
			(size 0.4318 0.4318)
			(layers "F.Cu" "F.Mask" "F.Paste")
			(net "M_J_DQ<57>")
		)
		(pad "AH27" smd circle
			(at -14.929612 -11.730228)
			(size 0.4318 0.4318)
			(layers "F.Cu" "F.Mask" "F.Paste")
			(net "GND")
		)
		(pad "AH29" smd circle
			(at -13.212572 -11.730228)
			(size 0.4318 0.4318)
			(layers "F.Cu" "F.Mask" "F.Paste")
			(net "M_J_DQ<55>")
		)
		(pad "AH31" smd circle
			(at -11.495532 -11.730228)
			(size 0.4318 0.4318)
			(layers "F.Cu" "F.Mask" "F.Paste")
			(net "M_J_DQ<49>")
		)
		(pad "AH33" smd circle
			(at -9.778492 -11.730228)
			(size 0.4318 0.4318)
			(layers "F.Cu" "F.Mask" "F.Paste")
			(net "GND")
		)
		(pad "AH35" smd circle
			(at -8.061452 -11.730228)
			(size 0.4318 0.4318)
			(layers "F.Cu" "F.Mask" "F.Paste")
			(net "GND")
		)
		(pad "AH37" smd circle
			(at -6.344412 -11.730228)
			(size 0.4318 0.4318)
			(layers "F.Cu" "F.Mask" "F.Paste")
			(net "PVCCIN_CPU1")
		)
		(pad "AH39" smd circle
			(at -4.627626 -11.730228)
			(size 0.4318 0.4318)
			(layers "F.Cu" "F.Mask" "F.Paste")
			(net "PVCCIN_CPU1")
		)
		(pad "AH41" smd circle
			(at -2.910586 -11.730228)
			(size 0.4318 0.4318)
			(layers "F.Cu" "F.Mask" "F.Paste")
			(net "PVCCIN_CPU1")
		)
		(pad "AH45" smd circle
			(at 2.052066 -13.530326)
			(size 0.508 0.508)
			(layers "F.Cu" "F.Mask" "F.Paste")
			(net "GND")
		)
		(pad "AH47" smd circle
			(at 3.769106 -13.530326)
			(size 0.4318 0.4318)
			(layers "F.Cu" "F.Mask" "F.Paste")
			(net "GND")
		)
		(pad "AH49" smd circle
			(at 5.485892 -13.530326)
			(size 0.4318 0.4318)
			(layers "F.Cu" "F.Mask" "F.Paste")
			(net "GND")
		)
		(pad "AH51" smd circle
			(at 7.202932 -13.530326)
			(size 0.4318 0.4318)
			(layers "F.Cu" "F.Mask" "F.Paste")
			(net "GND")
		)
		(pad "AH53" smd circle
			(at 8.919972 -13.530326)
			(size 0.4318 0.4318)
			(layers "F.Cu" "F.Mask" "F.Paste")
			(net "GND")
		)
		(pad "AH55" smd circle
			(at 10.637012 -13.530326)
			(size 0.4318 0.4318)
			(layers "F.Cu" "F.Mask" "F.Paste")
			(net "TP_CPU1_RSVD_231")
		)
		(pad "AH57" smd circle
			(at 12.354052 -13.530326)
			(size 0.4318 0.4318)
			(layers "F.Cu" "F.Mask" "F.Paste")
			(net "TP_CPU1_RSVD_230")
		)
		(pad "AH59" smd circle
			(at 14.071092 -13.530326)
			(size 0.4318 0.4318)
			(layers "F.Cu" "F.Mask" "F.Paste")
			(net "GND")
		)
		(pad "AH61" smd circle
			(at 15.787878 -13.530326)
			(size 0.4318 0.4318)
			(layers "F.Cu" "F.Mask" "F.Paste")
			(net "GND")
		)
		(pad "AH63" smd circle
			(at 17.504918 -13.530326)
			(size 0.4318 0.4318)
			(layers "F.Cu" "F.Mask" "F.Paste")
			(net "M_J_CPU_VREF")
		)
		(pad "AH65" smd circle
			(at 19.221958 -13.530326)
			(size 0.4318 0.4318)
			(layers "F.Cu" "F.Mask" "F.Paste")
			(net "GND")
		)
		(pad "AH67" smd circle
			(at 20.938998 -13.530326)
			(size 0.4318 0.4318)
			(layers "F.Cu" "F.Mask" "F.Paste")
			(net "M_G_DQS_DN<8>")
		)
		(pad "AH69" smd circle
			(at 22.656038 -13.530326)
			(size 0.4318 0.4318)
			(layers "F.Cu" "F.Mask" "F.Paste")
			(net "GND")
		)
		(pad "AH71" smd circle
			(at 24.373078 -13.530326)
			(size 0.4318 0.4318)
			(layers "F.Cu" "F.Mask" "F.Paste")
			(net "TP_CPU1_RSVD_229")
		)
		(pad "AH73" smd circle
			(at 26.090118 -13.530326)
			(size 0.4318 0.4318)
			(layers "F.Cu" "F.Mask" "F.Paste")
			(net "TP_CPU1_RSVD_228")
		)
		(pad "AH75" smd circle
			(at 27.806904 -13.530326)
			(size 0.4318 0.4318)
			(layers "F.Cu" "F.Mask" "F.Paste")
			(net "GND")
		)
		(pad "AH77" smd circle
			(at 29.523944 -13.530326)
			(size 0.4318 0.4318)
			(layers "F.Cu" "F.Mask" "F.Paste")
			(net "GND")
		)
		(pad "AH79" smd circle
			(at 31.240984 -13.530326)
			(size 0.4318 0.4318)
			(layers "F.Cu" "F.Mask" "F.Paste")
			(net "M_H_DQ<13>")
		)
		(pad "AH81" smd circle
			(at 32.958024 -13.530326)
			(size 0.4318 0.4318)
			(layers "F.Cu" "F.Mask" "F.Paste")
			(net "M_H_DQ<8>")
		)
		(pad "AH83" smd circle
			(at 34.675064 -13.530326)
			(size 0.4318 0.4318)
			(layers "F.Cu" "F.Mask" "F.Paste")
			(net "GND")
		)
		(pad "AH85" smd circle
			(at 36.392104 -13.530326)
			(size 0.4318 0.4318)
			(layers "F.Cu" "F.Mask" "F.Paste")
			(net "M_G_DQS_DP<0>")
		)
		(pad "AJ2" smd circle
			(at -36.392104 -11.234674)
			(size 0.4318 0.4318)
			(layers "F.Cu" "F.Mask" "F.Paste")
			(net "UPI_CPU1_CPU0_P0P0_DN<8>")
		)
		(pad "AJ4" smd circle
			(at -34.675064 -11.234674)
			(size 0.4318 0.4318)
			(layers "F.Cu" "F.Mask" "F.Paste")
			(net "GND")
		)
		(pad "AJ6" smd circle
			(at -32.958024 -11.234674)
			(size 0.4318 0.4318)
			(layers "F.Cu" "F.Mask" "F.Paste")
			(net "UPI_CPU0_CPU1_P0P0_DP<6>")
		)
		(pad "AJ8" smd circle
			(at -31.240984 -11.234674)
			(size 0.4318 0.4318)
			(layers "F.Cu" "F.Mask" "F.Paste")
			(net "GND")
		)
		(pad "AJ10" smd circle
			(at -29.523944 -11.234674)
			(size 0.4318 0.4318)
			(layers "F.Cu" "F.Mask" "F.Paste")
			(net "XDP_CPU_MBP0_N")
		)
		(pad "AJ12" smd circle
			(at -27.806904 -11.234674)
			(size 0.4318 0.4318)
			(layers "F.Cu" "F.Mask" "F.Paste")
			(net "H_CPU1_ERR0_G_N")
		)
		(pad "AJ14" smd circle
			(at -26.090118 -11.234674)
			(size 0.4318 0.4318)
			(layers "F.Cu" "F.Mask" "F.Paste")
			(net "PD_CPU1_EAR_N")
		)
		(pad "AJ18" smd circle
			(at -22.656038 -11.234674)
			(size 0.4318 0.4318)
			(layers "F.Cu" "F.Mask" "F.Paste")
			(net "SMB_DDR_GHJ_SCL_G_R")
		)
		(pad "AJ20" smd circle
			(at -20.938998 -11.234674)
			(size 0.4318 0.4318)
			(layers "F.Cu" "F.Mask" "F.Paste")
			(net "TP_CPU1_RSVD_227")
		)
		(pad "AJ22" smd circle
			(at -19.221958 -11.234674)
			(size 0.4318 0.4318)
			(layers "F.Cu" "F.Mask" "F.Paste")
			(net "GND")
		)
		(pad "AJ24" smd circle
			(at -17.504918 -11.234674)
			(size 0.4318 0.4318)
			(layers "F.Cu" "F.Mask" "F.Paste")
			(net "M_J_DQS_DN<7>")
		)
		(pad "AJ26" smd circle
			(at -15.787878 -11.234674)
			(size 0.4318 0.4318)
			(layers "F.Cu" "F.Mask" "F.Paste")
			(net "GND")
		)
		(pad "AJ28" smd circle
			(at -14.071092 -11.234674)
			(size 0.4318 0.4318)
			(layers "F.Cu" "F.Mask" "F.Paste")
			(net "GND")
		)
		(pad "AJ30" smd circle
			(at -12.354052 -11.234674)
			(size 0.4318 0.4318)
			(layers "F.Cu" "F.Mask" "F.Paste")
			(net "M_J_DQS_DN<6>")
		)
		(pad "AJ32" smd circle
			(at -10.637012 -11.234674)
			(size 0.4318 0.4318)
			(layers "F.Cu" "F.Mask" "F.Paste")
			(net "GND")
		)
		(pad "AJ34" smd circle
			(at -8.919972 -11.234674)
			(size 0.4318 0.4318)
			(layers "F.Cu" "F.Mask" "F.Paste")
			(net "GND")
		)
		(pad "AJ36" smd circle
			(at -7.202932 -11.234674)
			(size 0.4318 0.4318)
			(layers "F.Cu" "F.Mask" "F.Paste")
			(net "PVCCIN_CPU1")
		)
		(pad "AJ46" smd circle
			(at 2.910586 -13.034772)
			(size 0.4318 0.4318)
			(layers "F.Cu" "F.Mask" "F.Paste")
			(net "GND")
		)
		(pad "AJ48" smd circle
			(at 4.627626 -13.034772)
			(size 0.4318 0.4318)
			(layers "F.Cu" "F.Mask" "F.Paste")
			(net "GND")
		)
		(pad "AJ50" smd circle
			(at 6.344412 -13.034772)
			(size 0.4318 0.4318)
			(layers "F.Cu" "F.Mask" "F.Paste")
			(net "GND")
		)
		(pad "AJ52" smd circle
			(at 8.061452 -13.034772)
			(size 0.4318 0.4318)
			(layers "F.Cu" "F.Mask" "F.Paste")
			(net "GND")
		)
		(pad "AJ54" smd circle
			(at 9.778492 -13.034772)
			(size 0.4318 0.4318)
			(layers "F.Cu" "F.Mask" "F.Paste")
			(net "GND")
		)
		(pad "AJ56" smd circle
			(at 11.495532 -13.034772)
			(size 0.4318 0.4318)
			(layers "F.Cu" "F.Mask" "F.Paste")
			(net "TP_CPU1_RSVD_226")
		)
		(pad "AJ58" smd circle
			(at 13.212572 -13.034772)
			(size 0.4318 0.4318)
			(layers "F.Cu" "F.Mask" "F.Paste")
			(net "TP_CPU1_RSVD_225")
		)
		(pad "AJ60" smd circle
			(at 14.929612 -13.034772)
			(size 0.4318 0.4318)
			(layers "F.Cu" "F.Mask" "F.Paste")
			(net "TP_CPU1_RSVD_224")
		)
		(pad "AJ62" smd circle
			(at 16.646398 -13.034772)
			(size 0.4318 0.4318)
			(layers "F.Cu" "F.Mask" "F.Paste")
			(net "TP_CPU1_RSVD_223")
		)
		(pad "AJ64" smd circle
			(at 18.363438 -13.034772)
			(size 0.4318 0.4318)
			(layers "F.Cu" "F.Mask" "F.Paste")
			(net "M_G_CPU_VREF")
		)
		(pad "AJ66" smd circle
			(at 20.080478 -13.034772)
			(size 0.4318 0.4318)
			(layers "F.Cu" "F.Mask" "F.Paste")
			(net "GND")
		)
		(pad "AJ68" smd circle
			(at 21.797518 -13.034772)
			(size 0.4318 0.4318)
			(layers "F.Cu" "F.Mask" "F.Paste")
			(net "GND")
		)
		(pad "AJ70" smd circle
			(at 23.514558 -13.034772)
			(size 0.4318 0.4318)
			(layers "F.Cu" "F.Mask" "F.Paste")
			(net "TP_CPU1_RSVD_222")
		)
		(pad "AJ74" smd circle
			(at 26.948384 -13.034772)
			(size 0.4318 0.4318)
			(layers "F.Cu" "F.Mask" "F.Paste")
			(net "GND")
		)
		(pad "AJ76" smd circle
			(at 28.665424 -13.034772)
			(size 0.4318 0.4318)
			(layers "F.Cu" "F.Mask" "F.Paste")
			(net "M_J_DQ<3>")
		)
		(pad "AJ78" smd circle
			(at 30.382464 -13.034772)
			(size 0.4318 0.4318)
			(layers "F.Cu" "F.Mask" "F.Paste")
			(net "GND")
		)
		(pad "AJ80" smd circle
			(at 32.099504 -13.034772)
			(size 0.4318 0.4318)
			(layers "F.Cu" "F.Mask" "F.Paste")
			(net "M_H_DQ<12>")
		)
		(pad "AJ82" smd circle
			(at 33.816544 -13.034772)
			(size 0.4318 0.4318)
			(layers "F.Cu" "F.Mask" "F.Paste")
			(net "GND")
		)
		(pad "AJ84" smd circle
			(at 35.533584 -13.034772)
			(size 0.4318 0.4318)
			(layers "F.Cu" "F.Mask" "F.Paste")
			(net "M_G_DQS_DN<0>")
		)
		(pad "AJ86" smd custom
			(at 37.250624 -13.034772 270)
			(size 0.10795 0.10795)
			(layers "F.Cu" "F.Mask" "F.Paste")
			(net "GND")
			(options
				(clearance outline)
				(anchor circle)
			)
			(primitives
				(gr_poly
					(pts
						(arc
							(start 0.2159 -0.0381)
							(mid 0 -0.254)
							(end -0.2159 -0.0381)
						)
						(arc
							(start -0.2159 0.0381)
							(mid 0 0.254)
							(end 0.2159 0.0381)
						)
					)
					(width 0)
					(fill yes)
				)
			)
		)
		(pad "AK1" smd custom
			(at -37.250624 -10.739628 90)
			(size 0.10795 0.10795)
			(layers "F.Cu" "F.Mask" "F.Paste")
			(net "UPI_CPU1_CPU0_P0P0_DP<9>")
			(options
				(clearance outline)
				(anchor circle)
			)
			(primitives
				(gr_poly
					(pts
						(arc
							(start 0.2159 -0.0381)
							(mid 0 -0.254)
							(end -0.2159 -0.0381)
						)
						(arc
							(start -0.2159 0.0381)
							(mid 0 0.254)
							(end 0.2159 0.0381)
						)
					)
					(width 0)
					(fill yes)
				)
			)
		)
		(pad "AK3" smd circle
			(at -35.533584 -10.739628)
			(size 0.4318 0.4318)
			(layers "F.Cu" "F.Mask" "F.Paste")
			(net "UPI_CPU1_CPU0_P0P0_DN<10>")
		)
		(pad "AK5" smd circle
			(at -33.816544 -10.739628)
			(size 0.4318 0.4318)
			(layers "F.Cu" "F.Mask" "F.Paste")
			(net "UPI_CPU0_CPU1_P0P0_DN<7>")
		)
		(pad "AK7" smd circle
			(at -32.099504 -10.739628)
			(size 0.4318 0.4318)
			(layers "F.Cu" "F.Mask" "F.Paste")
			(net "UPI_CPU0_CPU1_P0P0_DP<8>")
		)
		(pad "AK9" smd circle
			(at -30.382464 -10.739628)
			(size 0.4318 0.4318)
			(layers "F.Cu" "F.Mask" "F.Paste")
			(net "GND")
		)
		(pad "AK11" smd circle
			(at -28.665424 -10.739628)
			(size 0.4318 0.4318)
			(layers "F.Cu" "F.Mask" "F.Paste")
			(net "H_CPU1_ERR1_G_N")
		)
		(pad "AK13" smd circle
			(at -26.948384 -10.739628)
			(size 0.4318 0.4318)
			(layers "F.Cu" "F.Mask" "F.Paste")
			(net "GND")
		)
		(pad "AK19" smd circle
			(at -21.797518 -10.739628)
			(size 0.4318 0.4318)
			(layers "F.Cu" "F.Mask" "F.Paste")
			(net "GND")
		)
		(pad "AK21" smd circle
			(at -20.080478 -10.739628)
			(size 0.4318 0.4318)
			(layers "F.Cu" "F.Mask" "F.Paste")
			(net "VSENSE_P1V8MCP_CPU1_SKT_VSEN")
		)
		(pad "AK23" smd circle
			(at -18.363438 -10.739628)
			(size 0.4318 0.4318)
			(layers "F.Cu" "F.Mask" "F.Paste")
			(net "GND")
		)
		(pad "AK25" smd circle
			(at -16.646398 -10.739628)
			(size 0.4318 0.4318)
			(layers "F.Cu" "F.Mask" "F.Paste")
			(net "GND")
		)
		(pad "AK27" smd circle
			(at -14.929612 -10.739628)
			(size 0.4318 0.4318)
			(layers "F.Cu" "F.Mask" "F.Paste")
			(net "CLK_322M_OSC_CPU1_RC_DP")
		)
		(pad "AK29" smd circle
			(at -13.212572 -10.739628)
			(size 0.4318 0.4318)
			(layers "F.Cu" "F.Mask" "F.Paste")
			(net "GND")
		)
		(pad "AK31" smd circle
			(at -11.495532 -10.739628)
			(size 0.4318 0.4318)
			(layers "F.Cu" "F.Mask" "F.Paste")
			(net "GND")
		)
		(pad "AK33" smd circle
			(at -9.778492 -10.739628)
			(size 0.4318 0.4318)
			(layers "F.Cu" "F.Mask" "F.Paste")
			(net "GND")
		)
		(pad "AK35" smd circle
			(at -8.061452 -10.739628)
			(size 0.4318 0.4318)
			(layers "F.Cu" "F.Mask" "F.Paste")
			(net "PVCCIN_CPU1")
		)
		(pad "AK45" smd circle
			(at 2.052066 -12.539726)
			(size 0.508 0.508)
			(layers "F.Cu" "F.Mask" "F.Paste")
			(net "PVCCIN_CPU1")
		)
		(pad "AK47" smd circle
			(at 3.769106 -12.539726)
			(size 0.4318 0.4318)
			(layers "F.Cu" "F.Mask" "F.Paste")
			(net "PVCCIN_CPU1")
		)
	)
)
